(kicad_pcb
	(version 20241229)
	(generator "pcbnew")
	(generator_version "9.0")
	(general
		(thickness 1.6296)
		(legacy_teardrops no)
	)
	(paper "A3")
	(title_block
		(title "Thunderbolt to 10GbE adapter")
		(date "2026-04-21")
		(rev "1.1.0")
		(company "Antmicro Ltd")
		(comment 1 "www.antmicro.com")
		(comment 9 "footprints 106-109 of 703")
	)
	(layers
		(0 "F.Cu" signal)
		(4 "In1.Cu" signal)
		(6 "In2.Cu" signal)
		(8 "In3.Cu" signal)
		(10 "In4.Cu" signal)
		(12 "In5.Cu" signal)
		(14 "In6.Cu" signal)
		(2 "B.Cu" signal)
		(9 "F.Adhes" user "F.Adhesive")
		(11 "B.Adhes" user "B.Adhesive")
		(13 "F.Paste" user)
		(15 "B.Paste" user)
		(5 "F.SilkS" user "F.Silkscreen")
		(7 "B.SilkS" user "B.Silkscreen")
		(1 "F.Mask" user)
		(3 "B.Mask" user)
		(17 "Dwgs.User" user "User.Drawings")
		(19 "Cmts.User" user "User.Comments")
		(21 "Eco1.User" user "User.Eco1")
		(23 "Eco2.User" user "User.Eco2")
		(25 "Edge.Cuts" user)
		(27 "Margin" user)
		(31 "F.CrtYd" user "F.Courtyard")
		(29 "B.CrtYd" user "B.Courtyard")
		(35 "F.Fab" user)
		(33 "B.Fab" user)
	)
	(footprint "antmicro-footprints:L_WE-PMFI-353220"
		(layer "F.Cu")
		(at 137.5 96.274999)
		(descr "https://www.we-online.com/en/components/products/WE-PMFI#/articles/WE-PMFI-353220")
		(property "Reference" "L4"
			(at 37.714999 -8.974998 0)
			(unlocked yes)
			(layer "F.SilkS")
			(effects
				(font
					(size 0.7 0.7)
					(thickness 0.15)
				)
			)
		)
		(property "Value" "L_2u2_5.8A_WE-PMFI-35329222"
			(at -2.6 3.1 0)
			(unlocked yes)
			(layer "F.Fab")
			(effects
				(font
					(size 0.7 0.7)
					(thickness 0.15)
				)
				(justify left bottom)
			)
		)
		(property "Datasheet" "https://www.we-online.com/components/products/datasheet/74479335329222.pdf"
			(at 0 0 0)
			(layer "F.Fab")
			(effects
				(font
					(size 0.7 0.7)
					(thickness 0.15)
				)
				(justify left bottom)
			)
		)
		(property "Description" "Power Inductors - SMD WE-PMFI 2.2 uH 5.8 A 40 mOhms AEC-Q200"
			(at 0 0 0)
			(layer "F.Fab")
			(effects
				(font
					(size 0.7 0.7)
					(thickness 0.15)
				)
				(justify left bottom)
			)
		)
		(property "Val" "2u2/5.8A"
			(at 0 0 0)
			(unlocked yes)
			(layer "F.Fab")
			(hide yes)
			(effects
				(font
					(size 1 1)
					(thickness 0.15)
				)
			)
		)
		(property "Manufacturer" "Würth Elektronik"
			(at 0 0 0)
			(unlocked yes)
			(layer "F.Fab")
			(hide yes)
			(effects
				(font
					(size 1 1)
					(thickness 0.15)
				)
			)
		)
		(property "MPN" "74479335329222"
			(at 0 0 0)
			(unlocked yes)
			(layer "F.Fab")
			(hide yes)
			(effects
				(font
					(size 1 1)
					(thickness 0.15)
				)
			)
		)
		(property "ISat" "7.8A"
			(at 0 0 0)
			(unlocked yes)
			(layer "F.Fab")
			(hide yes)
			(effects
				(font
					(size 1 1)
					(thickness 0.15)
				)
			)
		)
		(property "IMax" "5.8A"
			(at 0 0 0)
			(unlocked yes)
			(layer "F.Fab")
			(hide yes)
			(effects
				(font
					(size 1 1)
					(thickness 0.15)
				)
			)
		)
		(property "Size" "3.5x3.2x2.0"
			(at 0 0 0)
			(unlocked yes)
			(layer "F.Fab")
			(hide yes)
			(effects
				(font
					(size 1 1)
					(thickness 0.15)
				)
			)
		)
		(property "Author" "Antmicro"
			(at 0 0 0)
			(unlocked yes)
			(layer "F.Fab")
			(hide yes)
			(effects
				(font
					(size 1 1)
					(thickness 0.15)
				)
			)
		)
		(property "License" "Apache-2.0"
			(at 0 0 0)
			(unlocked yes)
			(layer "F.Fab")
			(hide yes)
			(effects
				(font
					(size 1 1)
					(thickness 0.15)
				)
			)
		)
		(sheetname "/X710 DCDC converters/")
		(sheetfile "DCDC_converters_X710.kicad_sch")
		(attr smd)
		(fp_line
			(start -1.75 -1.85)
			(end 1.75 -1.85)
			(stroke
				(width 0.15)
				(type solid)
			)
			(layer "F.SilkS")
		)
		(fp_line
			(start -1.75 1.85)
			(end 1.75 1.85)
			(stroke
				(width 0.15)
				(type solid)
			)
			(layer "F.SilkS")
		)
		(fp_rect
			(start -2.25 -2)
			(end 2.25 2)
			(stroke
				(width 0.05)
				(type solid)
			)
			(fill no)
			(layer "F.CrtYd")
		)
		(fp_rect
			(start -1.75 -1.6)
			(end 1.75 1.6)
			(stroke
				(width 0.15)
				(type solid)
			)
			(fill no)
			(layer "F.Fab")
		)
		(fp_text user "License: Apache-2.0"
			(at -2.5 6.75 0)
			(layer "F.Fab")
			(effects
				(font
					(size 0.7 0.7)
					(thickness 0.15)
				)
				(justify left bottom)
			)
		)
		(fp_text user "${REFERENCE}"
			(at -2.6 4.3 0)
			(unlocked yes)
			(layer "F.Fab")
			(effects
				(font
					(size 0.7 0.7)
					(thickness 0.15)
				)
				(justify left bottom)
			)
		)
		(fp_text user "Author: Antmicro"
			(at -2.5 5.55 0)
			(layer "F.Fab")
			(effects
				(font
					(size 0.7 0.7)
					(thickness 0.15)
				)
				(justify left bottom)
			)
		)
		(pad "1" smd rect
			(at -1.5 0)
			(size 1 3.5)
			(layers "F.Cu" "F.Mask" "F.Paste")
			(net 117 "/X710 DCDC converters/3V3_SW")
			(pintype "passive")
		)
		(pad "2" smd rect
			(at 1.5 0)
			(size 1 3.5)
			(layers "F.Cu" "F.Mask" "F.Paste")
			(net 334 "/X710 DCDC converters/+3V3_OUT")
			(pintype "passive")
		)
	)
	(footprint "antmicro-footprints:C_0603_1608Metric"
		(layer "F.Cu")
		(at 148.955001 66.024999 90)
		(descr "Capacitor SMD 0603")
		(tags "capacitor 0603")
		(property "Reference" "C221"
			(at 12.424999 20.045 90)
			(layer "F.SilkS")
			(effects
				(font
					(size 0.7 0.7)
					(thickness 0.15)
				)
			)
		)
		(property "Value" "C_10u_10V_X7R_0603"
			(at -1.42757 1.770288 90)
			(layer "F.Fab")
			(effects
				(font
					(size 0.7 0.7)
					(thickness 0.15)
				)
				(justify left bottom)
			)
		)
		(property "Datasheet" "https://www.murata.com/products/productdetail?partno=GRM188Z71A106KA73%23"
			(at 0 0 90)
			(layer "F.Fab")
			(hide yes)
			(effects
				(font
					(size 1.27 1.27)
					(thickness 0.15)
				)
			)
		)
		(property "Description" "SMD Multilayer Ceramic Capacitor,  10µF, 10V, 0603, ±10%, X7R"
			(at 0 0 90)
			(layer "F.Fab")
			(hide yes)
			(effects
				(font
					(size 1.27 1.27)
					(thickness 0.15)
				)
			)
		)
		(property "MPN" "GRM188Z71A106KA73D"
			(at 0 0 90)
			(unlocked yes)
			(layer "F.Fab")
			(hide yes)
			(effects
				(font
					(size 1 1)
					(thickness 0.15)
				)
			)
		)
		(property "Val" "10u"
			(at 0 0 90)
			(unlocked yes)
			(layer "F.Fab")
			(hide yes)
			(effects
				(font
					(size 1 1)
					(thickness 0.15)
				)
			)
		)
		(property "Voltage" "10V"
			(at 0 0 90)
			(unlocked yes)
			(layer "F.Fab")
			(hide yes)
			(effects
				(font
					(size 1 1)
					(thickness 0.15)
				)
			)
		)
		(property "Dielectric" "X7R"
			(at 0 0 90)
			(unlocked yes)
			(layer "F.Fab")
			(hide yes)
			(effects
				(font
					(size 1 1)
					(thickness 0.15)
				)
			)
		)
		(property "Manufacturer" "Murata"
			(at 0 0 90)
			(unlocked yes)
			(layer "F.Fab")
			(hide yes)
			(effects
				(font
					(size 1 1)
					(thickness 0.15)
				)
			)
		)
		(property "License" "Apache-2.0"
			(at 0 0 90)
			(unlocked yes)
			(layer "F.Fab")
			(hide yes)
			(effects
				(font
					(size 1 1)
					(thickness 0.15)
				)
			)
		)
		(property "Author" "Antmicro"
			(at 0 0 90)
			(unlocked yes)
			(layer "F.Fab")
			(hide yes)
			(effects
				(font
					(size 1 1)
					(thickness 0.15)
				)
			)
		)
		(sheetname "/X710-AT2 power/")
		(sheetfile "x710-at2-power.kicad_sch")
		(attr smd)
		(fp_line
			(start -0.15 -0.4)
			(end 0.15 -0.4)
			(stroke
				(width 0.15)
				(type solid)
			)
			(layer "F.SilkS")
		)
		(fp_line
			(start -0.15 0.4)
			(end 0.15 0.4)
			(stroke
				(width 0.15)
				(type solid)
			)
			(layer "F.SilkS")
		)
		(fp_rect
			(start -1.25 -0.65)
			(end 1.25 0.65)
			(stroke
				(width 0.05)
				(type solid)
			)
			(fill no)
			(layer "F.CrtYd")
		)
		(fp_rect
			(start -0.8 -0.4)
			(end 0.8 0.4)
			(stroke
				(width 0.15)
				(type solid)
			)
			(fill no)
			(layer "F.Fab")
		)
		(fp_text user "${REFERENCE}"
			(at -1.682 3.895 90)
			(layer "F.Fab")
			(effects
				(font
					(size 0.7 0.7)
					(thickness 0.15)
				)
				(justify left bottom)
			)
		)
		(fp_text user "License: Apache-2.0"
			(at -1.682 5.895 90)
			(layer "F.Fab")
			(effects
				(font
					(size 0.7 0.7)
					(thickness 0.15)
				)
				(justify left bottom)
			)
		)
		(fp_text user "Author: Antmicro"
			(at -1.682 4.894 90)
			(layer "F.Fab")
			(effects
				(font
					(size 0.7 0.7)
					(thickness 0.15)
				)
				(justify left bottom)
			)
		)
		(pad "1" smd roundrect
			(at -0.7 0 90)
			(size 0.8 1)
			(layers "F.Cu" "F.Mask" "F.Paste")
			(roundrect_rratio 0.2)
			(net 23 "GND")
			(pintype "passive")
		)
		(pad "2" smd roundrect
			(at 0.7 0 90)
			(size 0.8 1)
			(layers "F.Cu" "F.Mask" "F.Paste")
			(roundrect_rratio 0.2)
			(net 1 "VCCA")
			(pintype "passive")
		)
	)
	(footprint "antmicro-footprints:TSSOP-8_3x4.4mm_P0.65mm"
		(layer "F.Cu")
		(at 126 98.9 -90)
		(property "Reference" "U5"
			(at -1.9 1.8 270)
			(layer "F.SilkS")
			(effects
				(font
					(size 0.7 0.7)
					(thickness 0.15)
				)
				(justify left bottom)
			)
		)
		(property "Value" "SI52112-B6-GT"
			(at 0 3 270)
			(layer "F.Fab")
			(effects
				(font
					(size 0.7 0.7)
					(thickness 0.15)
				)
				(justify left bottom)
			)
		)
		(property "Datasheet" "https://www.skyworksinc.com/-/media/Skyworks/SL/documents/public/data-sheets/Si52112-B5-B6.pdf"
			(at 0 0 270)
			(layer "F.Fab")
			(hide yes)
			(effects
				(font
					(size 1.27 1.27)
					(thickness 0.15)
				)
			)
		)
		(property "Description" "Clock Generator, 100MHz, 2.97V to 3.63V, 2 Outputs, TSSOP-8"
			(at 0 0 270)
			(layer "F.Fab")
			(hide yes)
			(effects
				(font
					(size 1.27 1.27)
					(thickness 0.15)
				)
			)
		)
		(property "MPN" "SI52112-B6-GT"
			(at 0 0 270)
			(unlocked yes)
			(layer "F.Fab")
			(hide yes)
			(effects
				(font
					(size 1 1)
					(thickness 0.15)
				)
			)
		)
		(property "Manufacturer" "Skyworks Solutions"
			(at 0 0 270)
			(unlocked yes)
			(layer "F.Fab")
			(hide yes)
			(effects
				(font
					(size 1 1)
					(thickness 0.15)
				)
			)
		)
		(property "License" "Apache-2.0"
			(at 0 0 270)
			(unlocked yes)
			(layer "F.Fab")
			(hide yes)
			(effects
				(font
					(size 1 1)
					(thickness 0.15)
				)
			)
		)
		(property "Author" "Antmicro"
			(at 0 0 270)
			(unlocked yes)
			(layer "F.Fab")
			(hide yes)
			(effects
				(font
					(size 1 1)
					(thickness 0.15)
				)
			)
		)
		(sheetname "/TB Controller/")
		(sheetfile "tb.kicad_sch")
		(attr smd)
		(fp_line
			(start -2.3 1.6)
			(end -1.7 1.6)
			(stroke
				(width 0.15)
				(type solid)
			)
			(layer "F.SilkS")
		)
		(fp_line
			(start 2.3 1.6)
			(end 1.8 1.6)
			(stroke
				(width 0.15)
				(type solid)
			)
			(layer "F.SilkS")
		)
		(fp_line
			(start -2.3 1.3)
			(end -2.3 1.6)
			(stroke
				(width 0.15)
				(type solid)
			)
			(layer "F.SilkS")
		)
		(fp_line
			(start 2.3 1.25)
			(end 2.3 1.6)
			(stroke
				(width 0.15)
				(type solid)
			)
			(layer "F.SilkS")
		)
		(fp_line
			(start -2.3 -1.3)
			(end -2.3 -1.6)
			(stroke
				(width 0.15)
				(type solid)
			)
			(layer "F.SilkS")
		)
		(fp_line
			(start 2.3 -1.3)
			(end 2.3 -1.6)
			(stroke
				(width 0.15)
				(type solid)
			)
			(layer "F.SilkS")
		)
		(fp_line
			(start -2.3 -1.6)
			(end -1.7 -1.6)
			(stroke
				(width 0.15)
				(type solid)
			)
			(layer "F.SilkS")
		)
		(fp_line
			(start 2.3 -1.6)
			(end 1.8 -1.6)
			(stroke
				(width 0.15)
				(type solid)
			)
			(layer "F.SilkS")
		)
		(fp_circle
			(center -2.7 -1.51)
			(end -2.65 -1.51)
			(stroke
				(width 0.15)
				(type solid)
			)
			(fill yes)
			(layer "F.SilkS")
		)
		(fp_rect
			(start -3.45 -1.75)
			(end 3.45 1.75)
			(stroke
				(width 0.05)
				(type solid)
			)
			(fill no)
			(layer "F.CrtYd")
		)
		(fp_line
			(start -2.2 1.5)
			(end 2.2 1.5)
			(stroke
				(width 0.15)
				(type solid)
			)
			(layer "F.Fab")
		)
		(fp_line
			(start -2.2 -0.7)
			(end -2.2 1.5)
			(stroke
				(width 0.15)
				(type solid)
			)
			(layer "F.Fab")
		)
		(fp_line
			(start -2.2 -0.7)
			(end -1.4 -1.5)
			(stroke
				(width 0.15)
				(type solid)
			)
			(layer "F.Fab")
		)
		(fp_line
			(start -1.4 -1.5)
			(end 2.2 -1.5)
			(stroke
				(width 0.15)
				(type solid)
			)
			(layer "F.Fab")
		)
		(fp_line
			(start 2.2 -1.5)
			(end 2.2 1.5)
			(stroke
				(width 0.15)
				(type solid)
			)
			(layer "F.Fab")
		)
		(fp_text user "Author: Antmicro"
			(at -3.55 5 270)
			(layer "F.Fab")
			(effects
				(font
					(size 0.7 0.7)
					(thickness 0.15)
				)
				(justify left bottom)
			)
		)
		(fp_text user "${REFERENCE}"
			(at -3.55 7.4 270)
			(layer "F.Fab")
			(effects
				(font
					(size 0.7 0.7)
					(thickness 0.15)
				)
				(justify left bottom)
			)
		)
		(fp_text user "License: Apache-2.0"
			(at -3.55 6.2 270)
			(layer "F.Fab")
			(effects
				(font
					(size 0.7 0.7)
					(thickness 0.15)
				)
				(justify left bottom)
			)
		)
		(pad "1" smd rect
			(at -2.7 -0.975 270)
			(size 1.2 0.4)
			(layers "F.Cu" "F.Mask" "F.Paste")
			(net 57 "+3V3_TB")
			(pinfunction "VDD")
			(pintype "power_in")
		)
		(pad "2" smd rect
			(at -2.7 -0.325 270)
			(size 1.2 0.4)
			(layers "F.Cu" "F.Mask" "F.Paste")
			(net 400 "Net-(U5-XOUT)")
			(pinfunction "XOUT")
			(pintype "output")
		)
		(pad "3" smd rect
			(at -2.7 0.325 270)
			(size 1.2 0.4)
			(layers "F.Cu" "F.Mask" "F.Paste")
			(net 401 "Net-(U5-XIN{slash}CLKIN)")
			(pinfunction "XIN/CLKIN")
			(pintype "input")
		)
		(pad "4" smd rect
			(at -2.7 0.975 270)
			(size 1.2 0.4)
			(layers "F.Cu" "F.Mask" "F.Paste")
			(net 23 "GND")
			(pinfunction "GND")
			(pintype "power_in")
		)
		(pad "5" smd rect
			(at 2.7 0.975 270)
			(size 1.2 0.4)
			(layers "F.Cu" "F.Mask" "F.Paste")
			(net 214 "/TB Controller/PCIE_CLK_JHL_N")
			(pinfunction "DIFF1")
			(pintype "output")
		)
		(pad "6" smd rect
			(at 2.7 0.325 270)
			(size 1.2 0.4)
			(layers "F.Cu" "F.Mask" "F.Paste")
			(net 213 "/TB Controller/PCIE_CLK_JHL_P")
			(pinfunction "~{DIFF1}")
			(pintype "output")
		)
		(pad "7" smd rect
			(at 2.7 -0.325 270)
			(size 1.2 0.4)
			(layers "F.Cu" "F.Mask" "F.Paste")
			(net 394 "/TB Controller/REFCLK.-")
			(pinfunction "DIFF2")
			(pintype "output")
		)
		(pad "8" smd rect
			(at 2.7 -0.975 270)
			(size 1.2 0.4)
			(layers "F.Cu" "F.Mask" "F.Paste")
			(net 393 "/TB Controller/REFCLK.+")
			(pinfunction "~{DIFF2}")
			(pintype "output")
		)
	)
	(footprint "antmicro-footprints:C_0402_1005Metric"
		(layer "F.Cu")
		(at 130 98.7)
		(descr "Capacitor SMD 0402")
		(tags "capacitor SMD 0402")
		(property "Reference" "C39"
			(at 2.2 4.3 0)
			(layer "F.SilkS")
			(effects
				(font
					(size 0.7 0.7)
					(thickness 0.15)
				)
			)
		)
		(property "Value" "C_10p_0402"
			(at -1.022927 2.155213 0)
			(layer "F.Fab")
			(effects
				(font
					(size 0.7 0.7)
					(thickness 0.15)
				)
				(justify left bottom)
			)
		)
		(property "Datasheet" "https://www.murata.com/products/productdetail?partno=GCM1555C1H100GA16%23"
			(at 0 0 0)
			(layer "F.Fab")
			(hide yes)
			(effects
				(font
					(size 1.27 1.27)
					(thickness 0.15)
				)
			)
		)
		(property "Description" "SMD Multilayer Ceramic Capacitor, 10 pF, 50 V, 0402 [1005 Metric], ± 2%, C0G / NP0, GCM"
			(at 0 0 0)
			(layer "F.Fab")
			(hide yes)
			(effects
				(font
					(size 1.27 1.27)
					(thickness 0.15)
				)
			)
		)
		(property "MPN" "GCM1555C1H100GA16D"
			(at 0 0 0)
			(unlocked yes)
			(layer "F.Fab")
			(hide yes)
			(effects
				(font
					(size 1 1)
					(thickness 0.15)
				)
			)
		)
		(property "Manufacturer" "Murata"
			(at 0 0 0)
			(unlocked yes)
			(layer "F.Fab")
			(hide yes)
			(effects
				(font
					(size 1 1)
					(thickness 0.15)
				)
			)
		)
		(property "License" "Apache-2.0"
			(at 0 0 0)
			(unlocked yes)
			(layer "F.Fab")
			(hide yes)
			(effects
				(font
					(size 1 1)
					(thickness 0.15)
				)
			)
		)
		(property "Val" "10p"
			(at 0 0 0)
			(unlocked yes)
			(layer "F.Fab")
			(hide yes)
			(effects
				(font
					(size 1 1)
					(thickness 0.15)
				)
			)
		)
		(property "Voltage" "50V"
			(at 0 0 0)
			(unlocked yes)
			(layer "F.Fab")
			(hide yes)
			(effects
				(font
					(size 1 1)
					(thickness 0.15)
				)
			)
		)
		(property "Dielectric" "C0G"
			(at 0 0 0)
			(unlocked yes)
			(layer "F.Fab")
			(hide yes)
			(effects
				(font
					(size 1 1)
					(thickness 0.15)
				)
			)
		)
		(property "Author" "Antmicro"
			(at 0 0 0)
			(unlocked yes)
			(layer "F.Fab")
			(hide yes)
			(effects
				(font
					(size 1 1)
					(thickness 0.15)
				)
			)
		)
		(sheetname "/TB Controller/")
		(sheetfile "tb.kicad_sch")
		(attr smd)
		(fp_rect
			(start -0.925 -0.47)
			(end 0.925 0.47)
			(stroke
				(width 0.05)
				(type default)
			)
			(fill no)
			(layer "F.CrtYd")
		)
		(fp_line
			(start -0.494 -0.25)
			(end 0.504 -0.25)
			(stroke
				(width 0.15)
				(type solid)
			)
			(layer "F.Fab")
		)
		(fp_line
			(start -0.494 0.248)
			(end -0.494 -0.25)
			(stroke
				(width 0.15)
				(type solid)
			)
			(layer "F.Fab")
		)
		(fp_line
			(start 0.504 -0.25)
			(end 0.504 0.248)
			(stroke
				(width 0.15)
				(type solid)
			)
			(layer "F.Fab")
		)
		(fp_line
			(start 0.504 0.248)
			(end -0.494 0.248)
			(stroke
				(width 0.15)
				(type solid)
			)
			(layer "F.Fab")
		)
		(fp_text user "${REFERENCE}"
			(at -0.939 4.599 0)
			(layer "F.Fab")
			(effects
				(font
					(size 0.7 0.7)
					(thickness 0.15)
				)
				(justify left bottom)
			)
		)
		(fp_text user "License: Apache-2.0"
			(at -0.939 5.799 0)
			(layer "F.Fab")
			(effects
				(font
					(size 0.7 0.7)
					(thickness 0.15)
				)
				(justify left bottom)
			)
		)
		(fp_text user "Author: Antmicro"
			(at -0.939 3.399 0)
			(layer "F.Fab")
			(effects
				(font
					(size 0.7 0.7)
					(thickness 0.15)
				)
				(justify left bottom)
			)
		)
		(pad "1" smd roundrect
			(at -0.48 0)
			(size 0.59 0.64)
			(layers "F.Cu" "F.Mask" "F.Paste")
			(roundrect_rratio 0.25)
			(net 23 "GND")
			(pintype "passive")
		)
		(pad "2" smd roundrect
			(at 0.48 0)
			(size 0.59 0.64)
			(layers "F.Cu" "F.Mask" "F.Paste")
			(roundrect_rratio 0.25)
			(net 400 "Net-(U5-XOUT)")
			(pintype "passive")
		)
	)
)
